# T6G (Grand Teton) — schematic netlist excerpt (pin names and nets, part order shuffled) for the footprints in the layout excerpt that follows; sources: Cadence DE-HDL packaged netlist, KiCad conversion of 04192023_DAF0TMB3IC0_F0TG_MB_C_brd_V02_OCP.brd

PC125_4  Q_CAP  22UF 16V 20% X6S  pkg C0805  page 202 : A = SW_P12V_AUX_PVDDCR_CPU1_P0_FLT ; B = GND
C2261  Q_CAP  22UF 4V 20% X6S  pkg C0402  page 72 : A = PVDD11_S3_P1 ; B = GND
C2253  Q_CAP  22UF 4V 20% X6S  pkg C0402  page 69 : A = PVDDCR_CPU1_P0 ; B = GND

(kicad_pcb
	(version 20260206)
	(generator "pcbnew")
	(generator_version "10.0")
	(general
		(thickness 1.6)
		(legacy_teardrops no)
	)
	(paper "A4")
	(title_block
		(title "04192023_DAF0TMB3IC0_F0TG_MB_C_brd_V02_OCP.brd")
		(comment 1 "Grand Teton / footprints 6460-6462 of 8354")
	)
	(layers
		(0 "F.Cu" signal "TOP")
		(4 "In1.Cu" signal "GND")
		(6 "In2.Cu" signal "IN1")
		(8 "In3.Cu" signal "GND1")
		(10 "In4.Cu" signal "IN2")
		(12 "In5.Cu" signal "GND2")
		(14 "In6.Cu" signal "IN3")
		(16 "In7.Cu" signal "GND3")
		(18 "In8.Cu" signal "VCC")
		(20 "In9.Cu" signal "VCC1")
		(22 "In10.Cu" signal "GND4")
		(24 "In11.Cu" signal "IN4")
		(26 "In12.Cu" signal "GND5")
		(28 "In13.Cu" signal "IN5")
		(30 "In14.Cu" signal "GND6")
		(32 "In15.Cu" signal "IN6")
		(34 "In16.Cu" signal "GND7")
		(2 "B.Cu" signal "BOTTOM")
		(9 "F.Adhes" user "F.Adhesive")
		(11 "B.Adhes" user "B.Adhesive")
		(13 "F.Paste" user "Package Geometry/Pastemask Top")
		(15 "B.Paste" user "Package Geometry/Pastemask Bottom")
		(5 "F.SilkS" user "Ref Des/Silkscreen Top")
		(7 "B.SilkS" user "Ref Des/Silkscreen Bottom")
		(1 "F.Mask" user "Board Geometry/Soldermask Top")
		(3 "B.Mask" user "Board Geometry/Soldermask Bottom")
		(17 "Dwgs.User" user "User.Drawings")
		(19 "Cmts.User" user "User.Comments")
		(21 "Eco1.User" user "User.Eco1")
		(23 "Eco2.User" user "User.Eco2")
		(25 "Edge.Cuts" user "Board Geometry/Outline")
		(27 "Margin" user)
		(31 "F.CrtYd" user "Package Geometry/Place Bound Top")
		(29 "B.CrtYd" user "Package Geometry/Place Bound Bottom")
		(35 "F.Fab" user "Ref Des/Assembly Top")
		(33 "B.Fab" user "Ref Des/Assembly Bottom")
	)
	(footprint ""
		(layer "B.Cu")
		(at 104.561386 -266.005564)
		(property "Reference" "C2261"
			(at 0 0 0)
			(layer "B.SilkS")
			(hide yes)
			(effects
				(font
					(size 1.27 1.27)
				)
				(justify mirror)
			)
		)
		(property "Value" ""
			(at 0 0 0)
			(layer "B.Fab")
			(effects
				(font
					(size 1.27 1.27)
				)
				(justify mirror)
			)
		)
		(duplicate_pad_numbers_are_jumpers no)
		(fp_line
			(start -0.7874 -0.4064)
			(end -0.7874 0.4064)
			(stroke
				(width 0.1524)
				(type default)
			)
			(layer "B.SilkS")
		)
		(fp_line
			(start -0.7874 0.4064)
			(end 0.7874 0.4064)
			(stroke
				(width 0.1524)
				(type default)
			)
			(layer "B.SilkS")
		)
		(fp_line
			(start 0.7874 -0.4064)
			(end -0.7874 -0.4064)
			(stroke
				(width 0.1524)
				(type default)
			)
			(layer "B.SilkS")
		)
		(fp_line
			(start 0.7874 0.4064)
			(end 0.7874 -0.4064)
			(stroke
				(width 0.1524)
				(type default)
			)
			(layer "B.SilkS")
		)
		(fp_line
			(start -0.67945 -0.3048)
			(end -0.67945 0.3048)
			(stroke
				(width 0.1)
				(type default)
			)
			(layer "B.Fab")
		)
		(fp_line
			(start -0.67945 0.3048)
			(end -0.120396 0.3048)
			(stroke
				(width 0.1)
				(type default)
			)
			(layer "B.Fab")
		)
		(fp_line
			(start -0.12065 -0.3048)
			(end -0.67945 -0.3048)
			(stroke
				(width 0.1)
				(type default)
			)
			(layer "B.Fab")
		)
		(fp_line
			(start -0.12065 -0.2794)
			(end -0.12065 -0.3048)
			(stroke
				(width 0.1)
				(type default)
			)
			(layer "B.Fab")
		)
		(fp_line
			(start -0.120396 0.2794)
			(end 0.12065 0.2794)
			(stroke
				(width 0.1)
				(type default)
			)
			(layer "B.Fab")
		)
		(fp_line
			(start -0.120396 0.3048)
			(end -0.120396 0.2794)
			(stroke
				(width 0.1)
				(type default)
			)
			(layer "B.Fab")
		)
		(fp_line
			(start 0.12065 -0.305054)
			(end 0.12065 -0.2794)
			(stroke
				(width 0.1)
				(type default)
			)
			(layer "B.Fab")
		)
		(fp_line
			(start 0.12065 -0.2794)
			(end -0.12065 -0.2794)
			(stroke
				(width 0.1)
				(type default)
			)
			(layer "B.Fab")
		)
		(fp_line
			(start 0.12065 0.2794)
			(end 0.12065 0.3048)
			(stroke
				(width 0.1)
				(type default)
			)
			(layer "B.Fab")
		)
		(fp_line
			(start 0.12065 0.3048)
			(end 0.67945 0.3048)
			(stroke
				(width 0.1)
				(type default)
			)
			(layer "B.Fab")
		)
		(fp_line
			(start 0.67945 -0.305054)
			(end 0.12065 -0.305054)
			(stroke
				(width 0.1)
				(type default)
			)
			(layer "B.Fab")
		)
		(fp_line
			(start 0.67945 0.3048)
			(end 0.67945 -0.305054)
			(stroke
				(width 0.1)
				(type default)
			)
			(layer "B.Fab")
		)
		(pad "1" smd circle
			(at 0.40005 0 180)
			(size 0 0)
			(layers "B.Cu" "B.Mask" "B.Paste")
			(net "PVDD11_S3_P1")
		)
		(pad "2" smd circle
			(at -0.40005 0 180)
			(size 0 0)
			(layers "B.Cu" "B.Mask" "B.Paste")
			(net "GND")
		)
	)
	(footprint ""
		(layer "B.Cu")
		(at 354.406454 -267.52931)
		(property "Reference" "C2253"
			(at 0 0 0)
			(layer "B.SilkS")
			(hide yes)
			(effects
				(font
					(size 1.27 1.27)
				)
				(justify mirror)
			)
		)
		(property "Value" ""
			(at 0 0 0)
			(layer "B.Fab")
			(effects
				(font
					(size 1.27 1.27)
				)
				(justify mirror)
			)
		)
		(duplicate_pad_numbers_are_jumpers no)
		(fp_line
			(start -0.7874 -0.4064)
			(end -0.7874 0.4064)
			(stroke
				(width 0.1524)
				(type default)
			)
			(layer "B.SilkS")
		)
		(fp_line
			(start -0.7874 0.4064)
			(end 0.7874 0.4064)
			(stroke
				(width 0.1524)
				(type default)
			)
			(layer "B.SilkS")
		)
		(fp_line
			(start 0.7874 -0.4064)
			(end -0.7874 -0.4064)
			(stroke
				(width 0.1524)
				(type default)
			)
			(layer "B.SilkS")
		)
		(fp_line
			(start 0.7874 0.4064)
			(end 0.7874 -0.4064)
			(stroke
				(width 0.1524)
				(type default)
			)
			(layer "B.SilkS")
		)
		(fp_line
			(start -0.67945 -0.3048)
			(end -0.67945 0.3048)
			(stroke
				(width 0.1)
				(type default)
			)
			(layer "B.Fab")
		)
		(fp_line
			(start -0.67945 0.3048)
			(end -0.120396 0.3048)
			(stroke
				(width 0.1)
				(type default)
			)
			(layer "B.Fab")
		)
		(fp_line
			(start -0.12065 -0.3048)
			(end -0.67945 -0.3048)
			(stroke
				(width 0.1)
				(type default)
			)
			(layer "B.Fab")
		)
		(fp_line
			(start -0.12065 -0.2794)
			(end -0.12065 -0.3048)
			(stroke
				(width 0.1)
				(type default)
			)
			(layer "B.Fab")
		)
		(fp_line
			(start -0.120396 0.2794)
			(end 0.12065 0.2794)
			(stroke
				(width 0.1)
				(type default)
			)
			(layer "B.Fab")
		)
		(fp_line
			(start -0.120396 0.3048)
			(end -0.120396 0.2794)
			(stroke
				(width 0.1)
				(type default)
			)
			(layer "B.Fab")
		)
		(fp_line
			(start 0.12065 -0.305054)
			(end 0.12065 -0.2794)
			(stroke
				(width 0.1)
				(type default)
			)
			(layer "B.Fab")
		)
		(fp_line
			(start 0.12065 -0.2794)
			(end -0.12065 -0.2794)
			(stroke
				(width 0.1)
				(type default)
			)
			(layer "B.Fab")
		)
		(fp_line
			(start 0.12065 0.2794)
			(end 0.12065 0.3048)
			(stroke
				(width 0.1)
				(type default)
			)
			(layer "B.Fab")
		)
		(fp_line
			(start 0.12065 0.3048)
			(end 0.67945 0.3048)
			(stroke
				(width 0.1)
				(type default)
			)
			(layer "B.Fab")
		)
		(fp_line
			(start 0.67945 -0.305054)
			(end 0.12065 -0.305054)
			(stroke
				(width 0.1)
				(type default)
			)
			(layer "B.Fab")
		)
		(fp_line
			(start 0.67945 0.3048)
			(end 0.67945 -0.305054)
			(stroke
				(width 0.1)
				(type default)
			)
			(layer "B.Fab")
		)
		(pad "1" smd circle
			(at 0.40005 0 180)
			(size 0 0)
			(layers "B.Cu" "B.Mask" "B.Paste")
			(net "PVDDCR_CPU1_P0")
		)
		(pad "2" smd circle
			(at -0.40005 0 180)
			(size 0 0)
			(layers "B.Cu" "B.Mask" "B.Paste")
			(net "GND")
		)
	)
	(footprint ""
		(layer "B.Cu")
		(at 309.81777 -346.784168 90)
		(property "Reference" "PC125_4"
			(at 0 0 90)
			(layer "B.SilkS")
			(hide yes)
			(effects
				(font
					(size 1.27 1.27)
				)
				(justify mirror)
			)
		)
		(property "Value" ""
			(at 0 0 90)
			(layer "B.Fab")
			(effects
				(font
					(size 1.27 1.27)
				)
				(justify mirror)
			)
		)
		(duplicate_pad_numbers_are_jumpers no)
		(fp_line
			(start 1.524 -0.762)
			(end -1.524 -0.762)
			(stroke
				(width 0.1524)
				(type default)
			)
			(layer "B.SilkS")
		)
		(fp_line
			(start -1.524 -0.762)
			(end -1.524 0.762)
			(stroke
				(width 0.1524)
				(type default)
			)
			(layer "B.SilkS")
		)
		(fp_line
			(start 1.524 0.762)
			(end 1.524 -0.762)
			(stroke
				(width 0.1524)
				(type default)
			)
			(layer "B.SilkS")
		)
		(fp_line
			(start -1.524 0.762)
			(end 1.524 0.762)
			(stroke
				(width 0.1524)
				(type default)
			)
			(layer "B.SilkS")
		)
		(fp_line
			(start 1.1049 -0.724916)
			(end 1.1049 0.724916)
			(stroke
				(width 0.1)
				(type default)
			)
			(layer "B.Fab")
		)
		(fp_line
			(start -1.1049 -0.724916)
			(end 1.1049 -0.724916)
			(stroke
				(width 0.1)
				(type default)
			)
			(layer "B.Fab")
		)
		(fp_line
			(start 1.1049 0.724916)
			(end -1.1049 0.724916)
			(stroke
				(width 0.1)
				(type default)
			)
			(layer "B.Fab")
		)
		(fp_line
			(start -1.1049 0.724916)
			(end -1.1049 -0.724916)
			(stroke
				(width 0.1)
				(type default)
			)
			(layer "B.Fab")
		)
		(pad "1" smd rect
			(at 0.889 0 90)
			(size 1.016 1.27)
			(layers "B.Cu" "B.Mask" "B.Paste")
			(net "SW_P12V_AUX_PVDDCR_CPU1_P0_FLT")
		)
		(pad "2" smd rect
			(at -0.889 0 90)
			(size 1.016 1.27)
			(layers "B.Cu" "B.Mask" "B.Paste")
			(net "GND")
		)
	)
)
